(kicad_pcb
	(version 20241229)
	(generator "pcbnew")
	(generator_version "9.0")
	(general
		(thickness 1.61)
		(legacy_teardrops no)
	)
	(paper "A3")
	(title_block
		(title "SO-DIMM DDR5 Tester")
		(date "2025-11-26")
		(rev "1.3.0")
		(comment 9 "footprints 71-76 of 627")
	)
	(layers
		(0 "F.Cu" signal)
		(4 "In1.Cu" power)
		(6 "In2.Cu" mixed)
		(8 "In3.Cu" power)
		(10 "In4.Cu" mixed)
		(12 "In5.Cu" power)
		(14 "In6.Cu" mixed)
		(16 "In7.Cu" power)
		(18 "In8.Cu" power)
		(20 "In9.Cu" mixed)
		(22 "In10.Cu" power)
		(2 "B.Cu" signal)
		(9 "F.Adhes" user "F.Adhesive")
		(11 "B.Adhes" user "B.Adhesive")
		(13 "F.Paste" user)
		(15 "B.Paste" user)
		(5 "F.SilkS" user "F.Silkscreen")
		(7 "B.SilkS" user "B.Silkscreen")
		(1 "F.Mask" user)
		(3 "B.Mask" user)
		(17 "Dwgs.User" user "User.Drawings")
		(19 "Cmts.User" user "User.Comments")
		(21 "Eco1.User" user "User.Eco1")
		(23 "Eco2.User" user "User.Eco2")
		(25 "Edge.Cuts" user)
		(27 "Margin" user)
		(31 "F.CrtYd" user "F.Courtyard")
		(29 "B.CrtYd" user "B.Courtyard")
		(35 "F.Fab" user)
		(33 "B.Fab" user)
	)
	(footprint "antmicro-footprints:C_0603_1608Metric"
		(layer "F.Cu")
		(at 199.525 161.722)
		(descr "Capacitor SMD 0603")
		(tags "capacitor 0603")
		(property "Reference" "C192"
			(at -1.42757 -1.000252 0)
			(layer "F.SilkS")
			(hide yes)
			(effects
				(font
					(size 0.7 0.7)
					(thickness 0.15)
				)
				(justify left bottom)
			)
		)
		(property "Value" "C_22u_0603"
			(at -1.42757 1.770288 0)
			(layer "F.Fab")
			(effects
				(font
					(size 0.7 0.7)
					(thickness 0.15)
				)
				(justify left bottom)
			)
		)
		(property "Datasheet" "https://www.murata.com/products/productdetail?partno=GRM188R60J226MEA0%23"
			(at 0 0 0)
			(layer "F.Fab")
			(hide yes)
			(effects
				(font
					(size 1.27 1.27)
					(thickness 0.15)
				)
			)
		)
		(property "Author" "Antmicro"
			(at 0 0 0)
			(layer "F.Fab")
			(hide yes)
			(effects
				(font
					(size 1 1)
					(thickness 0.15)
				)
			)
		)
		(property "Dielectric" ""
			(at 0 0 0)
			(layer "F.Fab")
			(hide yes)
			(effects
				(font
					(size 1 1)
					(thickness 0.15)
				)
			)
		)
		(property "License" "Apache-2.0"
			(at 0 0 0)
			(layer "F.Fab")
			(hide yes)
			(effects
				(font
					(size 1 1)
					(thickness 0.15)
				)
			)
		)
		(property "MPN" "GRM188R60J226MEA0D"
			(at 0 0 0)
			(layer "F.Fab")
			(hide yes)
			(effects
				(font
					(size 1 1)
					(thickness 0.15)
				)
			)
		)
		(property "Manufacturer" "Murata"
			(at 0 0 0)
			(layer "F.Fab")
			(hide yes)
			(effects
				(font
					(size 1 1)
					(thickness 0.15)
				)
			)
		)
		(property "Val" "22u"
			(at 0 0 0)
			(layer "F.Fab")
			(hide yes)
			(effects
				(font
					(size 1 1)
					(thickness 0.15)
				)
			)
		)
		(property "Voltage" ""
			(at 0 0 0)
			(layer "F.Fab")
			(hide yes)
			(effects
				(font
					(size 1 1)
					(thickness 0.15)
				)
			)
		)
		(sheetname "/Supply/")
		(sheetfile "supply.kicad_sch")
		(attr smd)
		(fp_line
			(start -0.3 -0.3)
			(end 0.3 -0.3)
			(stroke
				(width 0.15)
				(type solid)
			)
			(layer "F.SilkS")
		)
		(fp_line
			(start -0.3 0.3)
			(end 0.3 0.3)
			(stroke
				(width 0.15)
				(type solid)
			)
			(layer "F.SilkS")
		)
		(fp_rect
			(start -1.24 -0.7)
			(end 1.24 0.7)
			(stroke
				(width 0.05)
				(type solid)
			)
			(fill no)
			(layer "F.CrtYd")
		)
		(fp_rect
			(start -0.8 -0.4)
			(end 0.8 0.4)
			(stroke
				(width 0.15)
				(type solid)
			)
			(fill no)
			(layer "F.Fab")
		)
		(pad "1" smd roundrect
			(at -0.7 0)
			(size 0.6 0.8)
			(layers "F.Cu" "F.Mask" "F.Paste")
			(roundrect_rratio 0.2)
			(net 1 "GND")
			(pintype "passive")
		)
		(pad "2" smd roundrect
			(at 0.7 0)
			(size 0.6 0.8)
			(layers "F.Cu" "F.Mask" "F.Paste")
			(roundrect_rratio 0.2)
			(net 53 "/Supply/1V1_local")
			(pintype "passive")
		)
	)
	(footprint "antmicro-footprints:SC70-3"
		(layer "F.Cu")
		(at 102.100501 115.476 180)
		(property "Reference" "Q9"
			(at 0 -1.6 180)
			(layer "F.SilkS")
			(hide yes)
			(effects
				(font
					(size 0.7 0.7)
					(thickness 0.15)
				)
				(justify left bottom)
			)
		)
		(property "Value" "BSS138PW,115"
			(at 0 2.3 180)
			(layer "F.Fab")
			(effects
				(font
					(size 0.7 0.7)
					(thickness 0.15)
				)
				(justify left bottom)
			)
		)
		(property "Datasheet" "https://assets.nexperia.com/documents/data-sheet/BSS138PW.pdf"
			(at 0 0 180)
			(layer "F.Fab")
			(hide yes)
			(effects
				(font
					(size 1.27 1.27)
					(thickness 0.15)
				)
			)
		)
		(property "Description" "Power MOSFET, N Channel, 60 V, 320 mA, 0.9 ohm, SOT-323, Surface Mount"
			(at 0 0 180)
			(layer "F.Fab")
			(hide yes)
			(effects
				(font
					(size 1.27 1.27)
					(thickness 0.15)
				)
			)
		)
		(property "Author" "Antmicro"
			(at 204.201002 230.952 0)
			(layer "F.Fab")
			(hide yes)
			(effects
				(font
					(size 1 1)
					(thickness 0.15)
				)
			)
		)
		(property "License" "Apache-2.0"
			(at 204.201002 230.952 0)
			(layer "F.Fab")
			(hide yes)
			(effects
				(font
					(size 1 1)
					(thickness 0.15)
				)
			)
		)
		(property "MPN" "BSS138PW,115"
			(at 204.201002 230.952 0)
			(layer "F.Fab")
			(hide yes)
			(effects
				(font
					(size 1 1)
					(thickness 0.15)
				)
			)
		)
		(property "Manufacturer" "Nexperia"
			(at 204.201002 230.952 0)
			(layer "F.Fab")
			(hide yes)
			(effects
				(font
					(size 1 1)
					(thickness 0.15)
				)
			)
		)
		(sheetname "/DDR5 SODIMM/")
		(sheetfile "ddr5-sodimm.kicad_sch")
		(attr smd)
		(fp_line
			(start 0.627 0.6)
			(end 0.627 1.001)
			(stroke
				(width 0.15)
				(type solid)
			)
			(layer "F.SilkS")
		)
		(fp_line
			(start 0.627 -0.6)
			(end 0.627 -0.999)
			(stroke
				(width 0.15)
				(type solid)
			)
			(layer "F.SilkS")
		)
		(fp_line
			(start -0.3 1)
			(end 0.627 1.001)
			(stroke
				(width 0.15)
				(type solid)
			)
			(layer "F.SilkS")
		)
		(fp_line
			(start -0.3 -1)
			(end 0.627 -0.999)
			(stroke
				(width 0.15)
				(type solid)
			)
			(layer "F.SilkS")
		)
		(fp_line
			(start 1.4 0.4)
			(end 0.9 0.4)
			(stroke
				(width 0.05)
				(type solid)
			)
			(layer "F.CrtYd")
		)
		(fp_line
			(start 1.4 -0.4)
			(end 1.4 0.4)
			(stroke
				(width 0.05)
				(type solid)
			)
			(layer "F.CrtYd")
		)
		(fp_line
			(start 0.9 1.3)
			(end -0.9 1.3)
			(stroke
				(width 0.05)
				(type solid)
			)
			(layer "F.CrtYd")
		)
		(fp_line
			(start 0.9 0.4)
			(end 0.9 1.3)
			(stroke
				(width 0.05)
				(type solid)
			)
			(layer "F.CrtYd")
		)
		(fp_line
			(start 0.9 -0.4)
			(end 1.4 -0.4)
			(stroke
				(width 0.05)
				(type solid)
			)
			(layer "F.CrtYd")
		)
		(fp_line
			(start 0.9 -1.3)
			(end 0.9 -0.4)
			(stroke
				(width 0.05)
				(type solid)
			)
			(layer "F.CrtYd")
		)
		(fp_line
			(start -0.9 1.3)
			(end -0.9 1)
			(stroke
				(width 0.05)
				(type solid)
			)
			(layer "F.CrtYd")
		)
		(fp_line
			(start -0.9 1)
			(end -1.4 1)
			(stroke
				(width 0.05)
				(type solid)
			)
			(layer "F.CrtYd")
		)
		(fp_line
			(start -0.9 -1)
			(end -1.4 -1)
			(stroke
				(width 0.05)
				(type solid)
			)
			(layer "F.CrtYd")
		)
		(fp_line
			(start -0.9 -1.3)
			(end 0.9 -1.3)
			(stroke
				(width 0.05)
				(type solid)
			)
			(layer "F.CrtYd")
		)
		(fp_line
			(start -0.9 -1.3)
			(end -0.9 -1)
			(stroke
				(width 0.05)
				(type solid)
			)
			(layer "F.CrtYd")
		)
		(fp_line
			(start -1.4 1)
			(end -1.4 -1)
			(stroke
				(width 0.05)
				(type solid)
			)
			(layer "F.CrtYd")
		)
		(fp_rect
			(start -0.623 -0.999)
			(end 0.627 1.001)
			(stroke
				(width 0.15)
				(type solid)
			)
			(fill no)
			(layer "F.Fab")
		)
		(pad "1" smd rect
			(at -1.051 -0.65 270)
			(size 0.6 0.6)
			(layers "F.Cu" "F.Mask" "F.Paste")
			(net 234 "HOT_SWAP_YELLOW")
			(pinfunction "G")
			(pintype "input")
		)
		(pad "2" smd rect
			(at -1.051 0.65 270)
			(size 0.6 0.6)
			(layers "F.Cu" "F.Mask" "F.Paste")
			(net 1 "GND")
			(pinfunction "S")
			(pintype "passive")
		)
		(pad "3" smd rect
			(at 1.05 0 270)
			(size 0.6 0.6)
			(layers "F.Cu" "F.Mask" "F.Paste")
			(net 358 "Net-(Q9-D)")
			(pinfunction "D")
			(pintype "passive")
		)
	)
	(footprint "antmicro-footprints:C_0402_1005Metric"
		(layer "F.Cu")
		(at 193.15 193.05 180)
		(descr "Capacitor SMD 0402")
		(tags "capacitor SMD 0402")
		(property "Reference" "C211"
			(at 0 -0.699 180)
			(layer "F.SilkS")
			(hide yes)
			(effects
				(font
					(size 0.7 0.7)
					(thickness 0.15)
				)
				(justify left bottom)
			)
		)
		(property "Value" "C_10u_6.3V_0402"
			(at -1.022927 2.155213 180)
			(layer "F.Fab")
			(effects
				(font
					(size 0.7 0.7)
					(thickness 0.15)
				)
				(justify left bottom)
			)
		)
		(property "Datasheet" "https://www.murata.com/products/productdetail?partno=GRM155R60J106ME15%23"
			(at 0 0 180)
			(layer "F.Fab")
			(hide yes)
			(effects
				(font
					(size 1.27 1.27)
					(thickness 0.15)
				)
			)
		)
		(property "Author" "Antmicro"
			(at 386.3 386.1 0)
			(layer "F.Fab")
			(hide yes)
			(effects
				(font
					(size 1 1)
					(thickness 0.15)
				)
			)
		)
		(property "Dielectric" "X5R"
			(at 386.3 386.1 0)
			(layer "F.Fab")
			(hide yes)
			(effects
				(font
					(size 1 1)
					(thickness 0.15)
				)
			)
		)
		(property "License" "Apache-2.0"
			(at 386.3 386.1 0)
			(layer "F.Fab")
			(hide yes)
			(effects
				(font
					(size 1 1)
					(thickness 0.15)
				)
			)
		)
		(property "MPN" "GRM155R60J106ME15D"
			(at 386.3 386.1 0)
			(layer "F.Fab")
			(hide yes)
			(effects
				(font
					(size 1 1)
					(thickness 0.15)
				)
			)
		)
		(property "Manufacturer" "Murata"
			(at 386.3 386.1 0)
			(layer "F.Fab")
			(hide yes)
			(effects
				(font
					(size 1 1)
					(thickness 0.15)
				)
			)
		)
		(property "Val" "10u"
			(at 386.3 386.1 0)
			(layer "F.Fab")
			(hide yes)
			(effects
				(font
					(size 1 1)
					(thickness 0.15)
				)
			)
		)
		(property "Voltage" "6.3V"
			(at 386.3 386.1 0)
			(layer "F.Fab")
			(hide yes)
			(effects
				(font
					(size 1 1)
					(thickness 0.15)
				)
			)
		)
		(sheetname "/Supply/")
		(sheetfile "supply.kicad_sch")
		(attr smd)
		(fp_rect
			(start -0.9659 -0.481258)
			(end 0.9649 0.458742)
			(stroke
				(width 0.05)
				(type solid)
			)
			(fill no)
			(layer "F.CrtYd")
		)
		(fp_line
			(start 0.499 0.248)
			(end -0.499 0.248)
			(stroke
				(width 0.15)
				(type solid)
			)
			(layer "F.Fab")
		)
		(fp_line
			(start 0.499 -0.25)
			(end 0.499 0.248)
			(stroke
				(width 0.15)
				(type solid)
			)
			(layer "F.Fab")
		)
		(fp_line
			(start -0.499 0.248)
			(end -0.499 -0.25)
			(stroke
				(width 0.15)
				(type solid)
			)
			(layer "F.Fab")
		)
		(fp_line
			(start -0.499 -0.25)
			(end 0.499 -0.25)
			(stroke
				(width 0.15)
				(type solid)
			)
			(layer "F.Fab")
		)
		(pad "1" smd roundrect
			(at -0.484 0 180)
			(size 0.59 0.64)
			(layers "F.Cu" "F.Mask" "F.Paste")
			(roundrect_rratio 0.25)
			(net 1 "GND")
			(pintype "passive")
		)
		(pad "2" smd roundrect
			(at 0.484 0 180)
			(size 0.59 0.64)
			(layers "F.Cu" "F.Mask" "F.Paste")
			(roundrect_rratio 0.25)
			(net 76 "/Supply/MGTAVTT_OUT")
			(pintype "passive")
		)
	)
	(footprint "antmicro-footprints:R_0402_1005Metric"
		(layer "F.Cu")
		(at 100.6 181.45 90)
		(descr "Resistor SMD 0402")
		(tags "resistor SMD 0402")
		(property "Reference" "R88"
			(at -1.122484 -0.772697 90)
			(layer "F.SilkS")
			(hide yes)
			(effects
				(font
					(size 0.7 0.7)
					(thickness 0.15)
				)
				(justify left bottom)
			)
		)
		(property "Value" "R_0R_0402"
			(at -1.011843 1.772047 90)
			(layer "F.Fab")
			(effects
				(font
					(size 0.7 0.7)
					(thickness 0.15)
				)
				(justify left bottom)
			)
		)
		(property "Datasheet" "https://industrial.panasonic.com/cdbs/www-data/pdf/RDA0000/AOA0000C301.pdf"
			(at 0 0 90)
			(layer "F.Fab")
			(hide yes)
			(effects
				(font
					(size 1.27 1.27)
					(thickness 0.15)
				)
			)
		)
		(property "Author" "Antmicro"
			(at 282.05 80.85 0)
			(layer "F.Fab")
			(hide yes)
			(effects
				(font
					(size 1 1)
					(thickness 0.15)
				)
			)
		)
		(property "Current" "1A"
			(at 282.05 80.85 0)
			(layer "F.Fab")
			(hide yes)
			(effects
				(font
					(size 1 1)
					(thickness 0.15)
				)
			)
		)
		(property "License" "Apache-2.0"
			(at 282.05 80.85 0)
			(layer "F.Fab")
			(hide yes)
			(effects
				(font
					(size 1 1)
					(thickness 0.15)
				)
			)
		)
		(property "MPN" "ERJ2GE0R00X"
			(at 282.05 80.85 0)
			(layer "F.Fab")
			(hide yes)
			(effects
				(font
					(size 1 1)
					(thickness 0.15)
				)
			)
		)
		(property "Manufacturer" "Panasonic"
			(at 282.05 80.85 0)
			(layer "F.Fab")
			(hide yes)
			(effects
				(font
					(size 1 1)
					(thickness 0.15)
				)
			)
		)
		(property "Tolerance" ""
			(at 282.05 80.85 0)
			(layer "F.Fab")
			(hide yes)
			(effects
				(font
					(size 1 1)
					(thickness 0.15)
				)
			)
		)
		(property "Val" "0R"
			(at 282.05 80.85 0)
			(layer "F.Fab")
			(hide yes)
			(effects
				(font
					(size 1 1)
					(thickness 0.15)
				)
			)
		)
		(sheetname "/Debug FTDI/")
		(sheetfile "debug-ftdi.kicad_sch")
		(attr smd)
		(fp_rect
			(start -0.93 -0.47)
			(end 0.93 0.47)
			(stroke
				(width 0.05)
				(type solid)
			)
			(fill no)
			(layer "F.CrtYd")
		)
		(fp_rect
			(start -0.5 -0.25)
			(end 0.5 0.25)
			(stroke
				(width 0.15)
				(type solid)
			)
			(fill no)
			(layer "F.Fab")
		)
		(pad "1" smd roundrect
			(at -0.485 0 90)
			(size 0.59 0.64)
			(layers "F.Cu" "F.Mask" "F.Paste")
			(roundrect_rratio 0.25)
			(net 383 "Net-(U13-OE)")
			(pintype "passive")
		)
		(pad "2" smd roundrect
			(at 0.485 0 90)
			(size 0.59 0.64)
			(layers "F.Cu" "F.Mask" "F.Paste")
			(roundrect_rratio 0.25)
			(net 652 "/Debug FTDI/BDBUS3")
			(pintype "passive")
		)
	)
	(footprint "antmicro-footprints:R_0402_1005Metric"
		(layer "F.Cu")
		(at 195.881001 161.922 180)
		(descr "Resistor SMD 0402")
		(tags "resistor SMD 0402")
		(property "Reference" "R157"
			(at 3.881001 -0.328 180)
			(layer "F.SilkS")
			(effects
				(font
					(size 0.7 0.7)
					(thickness 0.15)
				)
				(justify left bottom)
			)
		)
		(property "Value" "R_0R_0402"
			(at -1.011843 1.772047 180)
			(layer "F.Fab")
			(effects
				(font
					(size 0.7 0.7)
					(thickness 0.15)
				)
				(justify left bottom)
			)
		)
		(property "Datasheet" "https://industrial.panasonic.com/cdbs/www-data/pdf/RDA0000/AOA0000C301.pdf"
			(at 0 0 180)
			(layer "F.Fab")
			(hide yes)
			(effects
				(font
					(size 1.27 1.27)
					(thickness 0.15)
				)
			)
		)
		(property "Author" "Antmicro"
			(at 391.762002 323.844 0)
			(layer "F.Fab")
			(hide yes)
			(effects
				(font
					(size 1 1)
					(thickness 0.15)
				)
			)
		)
		(property "Current" "1A"
			(at 391.762002 323.844 0)
			(layer "F.Fab")
			(hide yes)
			(effects
				(font
					(size 1 1)
					(thickness 0.15)
				)
			)
		)
		(property "License" "Apache-2.0"
			(at 391.762002 323.844 0)
			(layer "F.Fab")
			(hide yes)
			(effects
				(font
					(size 1 1)
					(thickness 0.15)
				)
			)
		)
		(property "MPN" "ERJ2GE0R00X"
			(at 391.762002 323.844 0)
			(layer "F.Fab")
			(hide yes)
			(effects
				(font
					(size 1 1)
					(thickness 0.15)
				)
			)
		)
		(property "Manufacturer" "Panasonic"
			(at 391.762002 323.844 0)
			(layer "F.Fab")
			(hide yes)
			(effects
				(font
					(size 1 1)
					(thickness 0.15)
				)
			)
		)
		(property "Tolerance" ""
			(at 391.762002 323.844 0)
			(layer "F.Fab")
			(hide yes)
			(effects
				(font
					(size 1 1)
					(thickness 0.15)
				)
			)
		)
		(property "Val" "0R"
			(at 391.762002 323.844 0)
			(layer "F.Fab")
			(hide yes)
			(effects
				(font
					(size 1 1)
					(thickness 0.15)
				)
			)
		)
		(sheetname "/Supply/")
		(sheetfile "supply.kicad_sch")
		(attr smd)
		(fp_rect
			(start -0.93 -0.47)
			(end 0.93 0.47)
			(stroke
				(width 0.05)
				(type solid)
			)
			(fill no)
			(layer "F.CrtYd")
		)
		(fp_rect
			(start -0.5 -0.25)
			(end 0.5 0.25)
			(stroke
				(width 0.15)
				(type solid)
			)
			(fill no)
			(layer "F.Fab")
		)
		(pad "1" smd roundrect
			(at -0.485 0 180)
			(size 0.59 0.64)
			(layers "F.Cu" "F.Mask" "F.Paste")
			(roundrect_rratio 0.25)
			(net 208 "/Supply/FB6")
			(pintype "passive")
		)
		(pad "2" smd roundrect
			(at 0.485 0 180)
			(size 0.59 0.64)
			(layers "F.Cu" "F.Mask" "F.Paste")
			(roundrect_rratio 0.25)
			(net 60 "/Supply/5V_local")
			(pintype "passive")
		)
	)
	(footprint "antmicro-footprints:R_0402_1005Metric"
		(layer "F.Cu")
		(at 102 184.8 -90)
		(descr "Resistor SMD 0402")
		(tags "resistor SMD 0402")
		(property "Reference" "R95"
			(at -1.122484 -0.772697 270)
			(layer "F.SilkS")
			(hide yes)
			(effects
				(font
					(size 0.7 0.7)
					(thickness 0.15)
				)
				(justify left bottom)
			)
		)
		(property "Value" "R_4k7_0402"
			(at -1.011843 1.772047 270)
			(layer "F.Fab")
			(effects
				(font
					(size 0.7 0.7)
					(thickness 0.15)
				)
				(justify left bottom)
			)
		)
		(property "Datasheet" "https://www.bourns.com/docs/product-datasheets/cr.pdf"
			(at 0 0 270)
			(layer "F.Fab")
			(hide yes)
			(effects
				(font
					(size 1.27 1.27)
					(thickness 0.15)
				)
			)
		)
		(property "Author" "Antmicro"
			(at -82.8 286.8 0)
			(layer "F.Fab")
			(hide yes)
			(effects
				(font
					(size 1 1)
					(thickness 0.15)
				)
			)
		)
		(property "License" "Apache-2.0"
			(at -82.8 286.8 0)
			(layer "F.Fab")
			(hide yes)
			(effects
				(font
					(size 1 1)
					(thickness 0.15)
				)
			)
		)
		(property "MPN" "CR0402-FX-4701GLF"
			(at -82.8 286.8 0)
			(layer "F.Fab")
			(hide yes)
			(effects
				(font
					(size 1 1)
					(thickness 0.15)
				)
			)
		)
		(property "Manufacturer" "Bourns"
			(at -82.8 286.8 0)
			(layer "F.Fab")
			(hide yes)
			(effects
				(font
					(size 1 1)
					(thickness 0.15)
				)
			)
		)
		(property "Tolerance" "1%"
			(at -82.8 286.8 0)
			(layer "F.Fab")
			(hide yes)
			(effects
				(font
					(size 1 1)
					(thickness 0.15)
				)
			)
		)
		(property "Val" "4k7"
			(at -82.8 286.8 0)
			(layer "F.Fab")
			(hide yes)
			(effects
				(font
					(size 1 1)
					(thickness 0.15)
				)
			)
		)
		(sheetname "/Debug FTDI/")
		(sheetfile "debug-ftdi.kicad_sch")
		(attr smd)
		(fp_rect
			(start -0.93 -0.47)
			(end 0.93 0.47)
			(stroke
				(width 0.05)
				(type solid)
			)
			(fill no)
			(layer "F.CrtYd")
		)
		(fp_rect
			(start -0.5 -0.25)
			(end 0.5 0.25)
			(stroke
				(width 0.15)
				(type solid)
			)
			(fill no)
			(layer "F.Fab")
		)
		(pad "1" smd roundrect
			(at -0.485 0 270)
			(size 0.59 0.64)
			(layers "F.Cu" "F.Mask" "F.Paste")
			(roundrect_rratio 0.25)
			(net 41 "+3V3_AON")
			(pintype "passive")
		)
		(pad "2" smd roundrect
			(at 0.485 0 270)
			(size 0.59 0.64)
			(layers "F.Cu" "F.Mask" "F.Paste")
			(roundrect_rratio 0.25)
			(net 672 "/Debug FTDI/FTDI.SDA")
			(pintype "passive")
		)
	)
)
